(kicad_pcb
	(version 20221018)
	(generator pcbnew)
	(general
    (thickness 1.518)
  )
	(paper "A4")
	(title_block
    (title "Kria K26 Devboard")
    (date "2024-03-26")
    (rev "1.2.5")
    (comment 1 "www.antmicro.com")
    (comment 2 "Antmicro Ltd.")
		(comment 9 "footprints 437-438 of 660")
	)
	(layers
    (0 "F.Cu" mixed)
    (1 "In1.Cu" power)
    (2 "In2.Cu" mixed)
    (3 "In3.Cu" power)
    (4 "In4.Cu" mixed)
    (5 "In5.Cu" power)
    (6 "In6.Cu" mixed)
    (31 "B.Cu" power)
    (32 "B.Adhes" user "B.Adhesive")
    (33 "F.Adhes" user "F.Adhesive")
    (34 "B.Paste" user)
    (35 "F.Paste" user)
    (36 "B.SilkS" user "B.Silkscreen")
    (37 "F.SilkS" user "F.Silkscreen")
    (38 "B.Mask" user)
    (39 "F.Mask" user)
    (40 "Dwgs.User" user "User.Drawings")
    (41 "Cmts.User" user "User.Comments")
    (42 "Eco1.User" user "User.Eco1")
    (43 "Eco2.User" user "User.Eco2")
    (44 "Edge.Cuts" user)
    (45 "Margin" user)
    (46 "B.CrtYd" user "B.Courtyard")
    (47 "F.CrtYd" user "F.Courtyard")
    (48 "B.Fab" user)
    (49 "F.Fab" user)
  )
	(footprint "kria-k26-devboard-footprints:SOT-23-3" (layer "B.Cu")
    (at 119.85 146.05)
    (property "Author" "Antmicro")
    (property "License" "Apache-2.0")
    (property "MPN" "BSS123")
    (property "Manufacturer" "ON Semiconductor")
    (property "Sheetfile" "sd-3-card.kicad_sch")
    (property "Sheetname" "SD 3.0 card")
    (attr smd)
    (fp_text reference "Q1" (at 0.71 2.48 180) (layer "B.SilkS")
        (effects (font (size 0.7 0.7) (thickness 0.15)) (justify left bottom mirror))
    )
    (fp_text value "BSS123" (at -1.9 -2.7 180) (layer "B.Fab") hide
        (effects (font (size 0.7 0.7) (thickness 0.15)) (justify left bottom mirror))
    )
    (fp_text user "Author: Antmicro" (at -1.837 -5.3 180) (layer "B.Fab") hide
        (effects (font (size 0.7 0.7) (thickness 0.15)) (justify left bottom mirror))
    )
    (fp_text user "License: Apache-2.0" (at -1.8 -6.8 180) (layer "B.Fab") hide
        (effects (font (size 0.7 0.7) (thickness 0.15)) (justify left bottom mirror))
    )
    (fp_text user "${REFERENCE}" (at -1.837 -4 180) (layer "B.Fab") hide
        (effects (font (size 0.7 0.7) (thickness 0.15)) (justify left bottom mirror))
    )
    (fp_line (start -1.45 1.35) (end -0.85 1.35)
      (stroke (width 0.15) (type solid)) (layer "B.SilkS"))
    (fp_line (start -0.85 1.35) (end -0.7 1.5)
      (stroke (width 0.15) (type solid)) (layer "B.SilkS"))
    (fp_line (start -0.7 -1.5) (end -0.7 -1.35)
      (stroke (width 0.15) (type solid)) (layer "B.SilkS"))
    (fp_line (start 0.7 -1.5) (end -0.7 -1.5)
      (stroke (width 0.15) (type solid)) (layer "B.SilkS"))
    (fp_line (start 0.7 -0.4) (end 0.7 -1.5)
      (stroke (width 0.15) (type solid)) (layer "B.SilkS"))
    (fp_line (start 0.7 0.4) (end 0.7 1.5)
      (stroke (width 0.15) (type solid)) (layer "B.SilkS"))
    (fp_line (start 0.7 1.5) (end -0.7 1.5)
      (stroke (width 0.15) (type solid)) (layer "B.SilkS"))
    (fp_line (start -1.75 -1.4) (end -1.75 -0.5)
      (stroke (width 0.05) (type solid)) (layer "B.CrtYd"))
    (fp_line (start -1.75 -0.5) (end -0.85 -0.5)
      (stroke (width 0.05) (type solid)) (layer "B.CrtYd"))
    (fp_line (start -1.75 0.5) (end -1.75 1.4)
      (stroke (width 0.05) (type solid)) (layer "B.CrtYd"))
    (fp_line (start -0.9 1.4) (end -1.75 1.4)
      (stroke (width 0.05) (type solid)) (layer "B.CrtYd"))
    (fp_line (start -0.9 1.6) (end -0.9 1.4)
      (stroke (width 0.05) (type solid)) (layer "B.CrtYd"))
    (fp_line (start -0.9 1.6) (end 0.825 1.6)
      (stroke (width 0.05) (type solid)) (layer "B.CrtYd"))
    (fp_line (start -0.85 -1.65) (end -0.85 -1.4)
      (stroke (width 0.05) (type solid)) (layer "B.CrtYd"))
    (fp_line (start -0.85 -1.4) (end -1.75 -1.4)
      (stroke (width 0.05) (type solid)) (layer "B.CrtYd"))
    (fp_line (start -0.85 -0.5) (end -0.85 0.5)
      (stroke (width 0.05) (type solid)) (layer "B.CrtYd"))
    (fp_line (start -0.85 0.5) (end -1.75 0.5)
      (stroke (width 0.05) (type solid)) (layer "B.CrtYd"))
    (fp_line (start 0.825 0.45) (end 1.75 0.45)
      (stroke (width 0.05) (type solid)) (layer "B.CrtYd"))
    (fp_line (start 0.825 1.6) (end 0.825 0.45)
      (stroke (width 0.05) (type solid)) (layer "B.CrtYd"))
    (fp_line (start 0.85 -1.65) (end -0.85 -1.65)
      (stroke (width 0.05) (type solid)) (layer "B.CrtYd"))
    (fp_line (start 0.85 -0.45) (end 0.85 -1.65)
      (stroke (width 0.05) (type solid)) (layer "B.CrtYd"))
    (fp_line (start 1.75 -0.45) (end 0.85 -0.45)
      (stroke (width 0.05) (type solid)) (layer "B.CrtYd"))
    (fp_line (start 1.75 0.45) (end 1.75 -0.45)
      (stroke (width 0.05) (type solid)) (layer "B.CrtYd"))
    (fp_line (start -0.712 -1.519) (end 0.688 -1.519)
      (stroke (width 0.15) (type solid)) (layer "B.Fab"))
    (fp_line (start -0.712 1.325) (end -0.712 -1.523)
      (stroke (width 0.15) (type solid)) (layer "B.Fab"))
    (fp_line (start -0.437 1.526) (end -0.712 1.325)
      (stroke (width 0.15) (type solid)) (layer "B.Fab"))
    (fp_line (start -0.437 1.526) (end 0.688 1.526)
      (stroke (width 0.15) (type solid)) (layer "B.Fab"))
    (fp_line (start 0.688 -1.519) (end 0.688 1.52)
      (stroke (width 0.15) (type solid)) (layer "B.Fab"))
    (pad "1" smd roundrect (at -1.1 0.951) (size 1 0.6) (layers "B.Cu" "B.Paste" "B.Mask") (roundrect_rratio 0.15)
      (net 177 "/Reset logic/~{SD_CARD_RESET}") (pinfunction "G") (pintype "bidirectional"))
    (pad "2" smd roundrect (at -1.1 -0.949) (size 1 0.6) (layers "B.Cu" "B.Paste" "B.Mask") (roundrect_rratio 0.15)
      (net 1 "GND") (pinfunction "S") (pintype "bidirectional"))
    (pad "3" smd roundrect (at 1.1 0.0005) (size 1 0.6) (layers "B.Cu" "B.Paste" "B.Mask") (roundrect_rratio 0.15)
      (net 415 "Net-(Q1-D)") (pinfunction "D") (pintype "bidirectional"))
  )
	(footprint "kria-k26-devboard-footprints:SOT-23-3" (layer "B.Cu")
    (at 127.45 146.05)
    (property "Author" "Antmicro")
    (property "License" "Apache-2.0")
    (property "MPN" "AO3401A")
    (property "Manufacturer" "Alpha & Omega Semiconductor Inc.")
    (property "Sheetfile" "sd-3-card.kicad_sch")
    (property "Sheetname" "SD 3.0 card")
    (attr smd)
    (fp_text reference "Q2" (at 0.74 2.49 180) (layer "B.SilkS")
        (effects (font (size 0.7 0.7) (thickness 0.15)) (justify left bottom mirror))
    )
    (fp_text value "AO3401A" (at -1.9 -2.7 180) (layer "B.Fab") hide
        (effects (font (size 0.7 0.7) (thickness 0.15)) (justify left bottom mirror))
    )
    (fp_text user "License: Apache-2.0" (at -1.8 -6.8 180) (layer "B.Fab") hide
        (effects (font (size 0.7 0.7) (thickness 0.15)) (justify left bottom mirror))
    )
    (fp_text user "Author: Antmicro" (at -1.837 -5.3 180) (layer "B.Fab") hide
        (effects (font (size 0.7 0.7) (thickness 0.15)) (justify left bottom mirror))
    )
    (fp_text user "${REFERENCE}" (at -1.837 -4 180) (layer "B.Fab") hide
        (effects (font (size 0.7 0.7) (thickness 0.15)) (justify left bottom mirror))
    )
    (fp_line (start -1.45 1.35) (end -0.85 1.35)
      (stroke (width 0.15) (type solid)) (layer "B.SilkS"))
    (fp_line (start -0.85 1.35) (end -0.7 1.5)
      (stroke (width 0.15) (type solid)) (layer "B.SilkS"))
    (fp_line (start -0.7 -1.5) (end -0.7 -1.35)
      (stroke (width 0.15) (type solid)) (layer "B.SilkS"))
    (fp_line (start 0.7 -1.5) (end -0.7 -1.5)
      (stroke (width 0.15) (type solid)) (layer "B.SilkS"))
    (fp_line (start 0.7 -0.4) (end 0.7 -1.5)
      (stroke (width 0.15) (type solid)) (layer "B.SilkS"))
    (fp_line (start 0.7 0.4) (end 0.7 1.5)
      (stroke (width 0.15) (type solid)) (layer "B.SilkS"))
    (fp_line (start 0.7 1.5) (end -0.7 1.5)
      (stroke (width 0.15) (type solid)) (layer "B.SilkS"))
    (fp_line (start -1.75 -1.4) (end -1.75 -0.5)
      (stroke (width 0.05) (type solid)) (layer "B.CrtYd"))
    (fp_line (start -1.75 -0.5) (end -0.85 -0.5)
      (stroke (width 0.05) (type solid)) (layer "B.CrtYd"))
    (fp_line (start -1.75 0.5) (end -1.75 1.4)
      (stroke (width 0.05) (type solid)) (layer "B.CrtYd"))
    (fp_line (start -0.9 1.4) (end -1.75 1.4)
      (stroke (width 0.05) (type solid)) (layer "B.CrtYd"))
    (fp_line (start -0.9 1.6) (end -0.9 1.4)
      (stroke (width 0.05) (type solid)) (layer "B.CrtYd"))
    (fp_line (start -0.9 1.6) (end 0.825 1.6)
      (stroke (width 0.05) (type solid)) (layer "B.CrtYd"))
    (fp_line (start -0.85 -1.65) (end -0.85 -1.4)
      (stroke (width 0.05) (type solid)) (layer "B.CrtYd"))
    (fp_line (start -0.85 -1.4) (end -1.75 -1.4)
      (stroke (width 0.05) (type solid)) (layer "B.CrtYd"))
    (fp_line (start -0.85 -0.5) (end -0.85 0.5)
      (stroke (width 0.05) (type solid)) (layer "B.CrtYd"))
    (fp_line (start -0.85 0.5) (end -1.75 0.5)
      (stroke (width 0.05) (type solid)) (layer "B.CrtYd"))
    (fp_line (start 0.825 0.45) (end 1.75 0.45)
      (stroke (width 0.05) (type solid)) (layer "B.CrtYd"))
    (fp_line (start 0.825 1.6) (end 0.825 0.45)
      (stroke (width 0.05) (type solid)) (layer "B.CrtYd"))
    (fp_line (start 0.85 -1.65) (end -0.85 -1.65)
      (stroke (width 0.05) (type solid)) (layer "B.CrtYd"))
    (fp_line (start 0.85 -0.45) (end 0.85 -1.65)
      (stroke (width 0.05) (type solid)) (layer "B.CrtYd"))
    (fp_line (start 1.75 -0.45) (end 0.85 -0.45)
      (stroke (width 0.05) (type solid)) (layer "B.CrtYd"))
    (fp_line (start 1.75 0.45) (end 1.75 -0.45)
      (stroke (width 0.05) (type solid)) (layer "B.CrtYd"))
    (fp_line (start -0.712 -1.519) (end 0.688 -1.519)
      (stroke (width 0.15) (type solid)) (layer "B.Fab"))
    (fp_line (start -0.712 1.325) (end -0.712 -1.523)
      (stroke (width 0.15) (type solid)) (layer "B.Fab"))
    (fp_line (start -0.437 1.526) (end -0.712 1.325)
      (stroke (width 0.15) (type solid)) (layer "B.Fab"))
    (fp_line (start -0.437 1.526) (end 0.688 1.526)
      (stroke (width 0.15) (type solid)) (layer "B.Fab"))
    (fp_line (start 0.688 -1.519) (end 0.688 1.52)
      (stroke (width 0.15) (type solid)) (layer "B.Fab"))
    (pad "1" smd roundrect (at -1.1 0.951) (size 1 0.6) (layers "B.Cu" "B.Paste" "B.Mask") (roundrect_rratio 0.15)
      (net 131 "Net-(Q2-G)") (pinfunction "G") (pintype "bidirectional"))
    (pad "2" smd roundrect (at -1.1 -0.949) (size 1 0.6) (layers "B.Cu" "B.Paste" "B.Mask") (roundrect_rratio 0.15)
      (net 15 "PS_3V3") (pinfunction "S") (pintype "bidirectional"))
    (pad "3" smd roundrect (at 1.1 0.0005) (size 1 0.6) (layers "B.Cu" "B.Paste" "B.Mask") (roundrect_rratio 0.15)
      (net 317 "/SD 3.0 card/SD_VDD") (pinfunction "D") (pintype "bidirectional"))
  )
)
